# BASEBOARD_FAB2 (Tioga Pass) — schematic netlist excerpt (pin names and nets, part order shuffled) for the footprints in the layout excerpt that follows; sources: Cadence DE-HDL packaged netlist, KiCad conversion of Wiwynn_Tioga_Pass_MB.brd

C3A5  CAP_A  47UF 4V 20% X5R  pkg 0603V  page 228 : A = PVDDQ_KLM ; B = GND
RT35  1R3F-GP  1%  pkg RCL_GP  page 216 : \1\ = VR_PVDDQ_ABC_PH2_SW_RC ; \2\ = GND
CT39  CAP_A  0.1UF 16V 10% X7R  pkg 0402V  page 203 : A = VR_PVCCIN_CPU0_AIREF3 ; B = GND

(kicad_pcb
	(version 20260206)
	(generator "pcbnew")
	(generator_version "10.0")
	(general
		(thickness 1.6)
		(legacy_teardrops no)
	)
	(paper "A4")
	(title_block
		(title "Wiwynn_Tioga_Pass_MB.brd")
		(comment 1 "Tioga Pass / footprints 2009-2011 of 4770")
	)
	(layers
		(0 "F.Cu" signal "TOP")
		(4 "In1.Cu" signal "L2GND")
		(6 "In2.Cu" signal "L3")
		(8 "In3.Cu" signal "L4GND")
		(10 "In4.Cu" signal "L5")
		(12 "In5.Cu" signal "L6GND")
		(14 "In6.Cu" signal "L7VCC")
		(16 "In7.Cu" signal "L8VCC")
		(18 "In8.Cu" signal "L9GND")
		(20 "In9.Cu" signal "L10")
		(22 "In10.Cu" signal "L11GND")
		(24 "In11.Cu" signal "L12")
		(26 "In12.Cu" signal "L13GND")
		(2 "B.Cu" signal "BOTTOM")
		(9 "F.Adhes" user "F.Adhesive")
		(11 "B.Adhes" user "B.Adhesive")
		(13 "F.Paste" user "Package Geometry/Pastemask Top")
		(15 "B.Paste" user "Package Geometry/Pastemask Bottom")
		(5 "F.SilkS" user "Ref Des/Silkscreen Top")
		(7 "B.SilkS" user "Ref Des/Silkscreen Bottom")
		(1 "F.Mask" user "Board Geometry/Soldermask Top")
		(3 "B.Mask" user "Board Geometry/Soldermask Bottom")
		(17 "Dwgs.User" user "User.Drawings")
		(19 "Cmts.User" user "User.Comments")
		(21 "Eco1.User" user "User.Eco1")
		(23 "Eco2.User" user "User.Eco2")
		(25 "Edge.Cuts" user "Board Geometry/Outline")
		(27 "Margin" user)
		(31 "F.CrtYd" user "Package Geometry/Place Bound Top")
		(29 "B.CrtYd" user "Package Geometry/Place Bound Bottom")
		(35 "F.Fab" user "Ref Des/Assembly Top")
		(33 "B.Fab" user "Ref Des/Assembly Bottom")
	)
	(footprint ""
		(layer "F.Cu")
		(at 343.95664 -2.44348 90)
		(property "Reference" "RT35"
			(at 0 0 90)
			(layer "F.SilkS")
			(hide yes)
			(effects
				(font
					(size 1.27 1.27)
				)
			)
		)
		(property "Value" "*"
			(at -0.0254 -2.6289 90)
			(unlocked yes)
			(layer "F.Fab")
			(hide yes)
			(effects
				(font
					(size 1.27 1.016)
					(thickness 0.1524)
				)
			)
		)
		(property "Device Type" "1R3F-GP_RCL_GP-1R3F-GP,64.1R00A"
			(at -0.0254 -4.1529 90)
			(unlocked yes)
			(layer "F.Fab")
			(hide yes)
			(effects
				(font
					(size 1.27 1.016)
					(thickness 0.1524)
				)
			)
		)
		(duplicate_pad_numbers_are_jumpers no)
		(fp_line
			(start 0.2032 0)
			(end 0.4826 0)
			(stroke
				(width 0.2032)
				(type default)
			)
			(layer "F.SilkS")
		)
		(fp_line
			(start -0.4826 0)
			(end -0.2032 0)
			(stroke
				(width 0.2032)
				(type default)
			)
			(layer "F.SilkS")
		)
		(fp_rect
			(start -0.5842 1.3335)
			(end 0.5842 -1.3335)
			(stroke
				(width 0)
				(type default)
			)
			(fill no)
			(layer "F.CrtYd")
		)
		(fp_rect
			(start -0.5842 1.3335)
			(end 0.5842 -1.3335)
			(stroke
				(width 0)
				(type default)
			)
			(fill no)
			(layer "F.Fab")
		)
		(pad "1" smd custom
			(at 0 -0.762 90)
			(size 0.2159 0.2159)
			(layers "F.Cu" "F.Mask" "F.Paste")
			(net "VR_PVDDQ_ABC_PH2_SW_RC")
			(options
				(clearance outline)
				(anchor circle)
			)
			(primitives
				(gr_poly
					(pts
						(arc
							(start -0.3302 -0.4318)
							(mid -0.402042 -0.402042)
							(end -0.4318 -0.3302)
						)
						(arc
							(start -0.4318 0.3302)
							(mid -0.402042 0.402042)
							(end -0.3302 0.4318)
						)
						(arc
							(start 0.3302 0.4318)
							(mid 0.402042 0.402042)
							(end 0.4318 0.3302)
						)
						(arc
							(start 0.4318 -0.3302)
							(mid 0.402042 -0.402042)
							(end 0.3302 -0.4318)
						)
					)
					(width 0)
					(fill yes)
				)
			)
		)
		(pad "2" smd custom
			(at 0 0.762 90)
			(size 0.2159 0.2159)
			(layers "F.Cu" "F.Mask" "F.Paste")
			(net "GND")
			(options
				(clearance outline)
				(anchor circle)
			)
			(primitives
				(gr_poly
					(pts
						(arc
							(start -0.3302 -0.4318)
							(mid -0.402042 -0.402042)
							(end -0.4318 -0.3302)
						)
						(arc
							(start -0.4318 0.3302)
							(mid -0.402042 0.402042)
							(end -0.3302 0.4318)
						)
						(arc
							(start 0.3302 0.4318)
							(mid 0.402042 0.402042)
							(end 0.4318 0.3302)
						)
						(arc
							(start 0.4318 -0.3302)
							(mid 0.402042 -0.402042)
							(end 0.3302 -0.4318)
						)
					)
					(width 0)
					(fill yes)
				)
			)
		)
	)
	(footprint ""
		(layer "F.Cu")
		(at 194.344036 -69.770244)
		(property "Reference" "CT39"
			(at -0.35687 -5.5118 270)
			(unlocked yes)
			(layer "F.SilkS")
			(effects
				(font
					(size 0.7874 0.5842)
					(thickness 0.1524)
				)
				(justify left)
			)
		)
		(property "Value" ""
			(at 0 0 0)
			(layer "F.Fab")
			(effects
				(font
					(size 1.27 1.27)
				)
			)
		)
		(duplicate_pad_numbers_are_jumpers no)
		(fp_poly
			(pts
				(xy 0.3048 -0.1016) (xy 0.3048 0.9906) (xy -0.3048 0.9906) (xy -0.3048 -0.1016)
			)
			(stroke
				(width 0)
				(type default)
			)
			(fill no)
			(layer "F.CrtYd")
		)
		(fp_line
			(start -0.3048 -0.1016)
			(end -0.3048 0.9906)
			(stroke
				(width 0.1)
				(type default)
			)
			(layer "F.Fab")
		)
		(fp_line
			(start -0.3048 0.9906)
			(end 0.3048 0.9906)
			(stroke
				(width 0.1)
				(type default)
			)
			(layer "F.Fab")
		)
		(fp_line
			(start 0.3048 -0.1016)
			(end -0.3048 -0.1016)
			(stroke
				(width 0.1)
				(type default)
			)
			(layer "F.Fab")
		)
		(fp_line
			(start 0.3048 0.9906)
			(end 0.3048 -0.1016)
			(stroke
				(width 0.1)
				(type default)
			)
			(layer "F.Fab")
		)
		(pad "1" smd rect
			(at 0 0)
			(size 0.508 0.508)
			(layers "F.Cu" "F.Mask" "F.Paste")
			(net "VR_PVCCIN_CPU0_AIREF3")
		)
		(pad "2" smd rect
			(at 0 0.889)
			(size 0.508 0.508)
			(layers "F.Cu" "F.Mask" "F.Paste")
			(net "GND")
		)
		(zone
			(layer "F.Cu")
			(hatch none 0.5)
			(connect_pads
				(clearance 0)
			)
			(min_thickness 0.25)
			(keepout
				(tracks allowed)
				(vias not_allowed)
				(pads allowed)
				(copperpour not_allowed)
				(footprints allowed)
			)
			(placement
				(enabled no)
				(sheetname "")
			)
			(fill
				(thermal_gap 0.5)
				(thermal_bridge_width 0.5)
				(island_removal_mode 0)
			)
			(polygon
				(pts
					(xy 194.090036 -69.516244) (xy 194.598036 -69.516244) (xy 194.598036 -69.135244) (xy 194.090036 -69.135244)
				)
			)
		)
		(zone
			(layer "F.Cu")
			(hatch none 0.5)
			(connect_pads
				(clearance 0)
			)
			(min_thickness 0.25)
			(keepout
				(tracks not_allowed)
				(vias allowed)
				(pads allowed)
				(copperpour not_allowed)
				(footprints allowed)
			)
			(placement
				(enabled no)
				(sheetname "")
			)
			(fill
				(thermal_gap 0.5)
				(thermal_bridge_width 0.5)
				(island_removal_mode 0)
			)
			(polygon
				(pts
					(xy 194.090036 -69.135244) (xy 194.598036 -69.135244) (xy 194.598036 -69.516244) (xy 194.090036 -69.516244)
				)
			)
		)
	)
	(footprint ""
		(layer "F.Cu")
		(at 107.8611 -140.208 90)
		(property "Reference" "C3A5"
			(at 1.848866 0.752348 90)
			(unlocked yes)
			(layer "F.SilkS")
			(effects
				(font
					(size 1.27 0.9652)
					(thickness 0.1524)
				)
			)
		)
		(property "Value" ""
			(at 0 0 90)
			(layer "F.Fab")
			(effects
				(font
					(size 1.27 1.27)
				)
			)
		)
		(duplicate_pad_numbers_are_jumpers no)
		(fp_rect
			(start -0.500126 1.598422)
			(end 0.500126 -0.201422)
			(stroke
				(width 0)
				(type default)
			)
			(fill no)
			(layer "F.CrtYd")
		)
		(fp_line
			(start 0.500126 -0.201422)
			(end 0.500126 1.598422)
			(stroke
				(width 0.1)
				(type default)
			)
			(layer "F.Fab")
		)
		(fp_line
			(start -0.500126 -0.201422)
			(end 0.500126 -0.201422)
			(stroke
				(width 0.1)
				(type default)
			)
			(layer "F.Fab")
		)
		(fp_line
			(start 0.500126 1.598422)
			(end -0.500126 1.598422)
			(stroke
				(width 0.1)
				(type default)
			)
			(layer "F.Fab")
		)
		(fp_line
			(start -0.500126 1.598422)
			(end -0.500126 -0.201422)
			(stroke
				(width 0.1)
				(type default)
			)
			(layer "F.Fab")
		)
		(pad "1" smd rect
			(at 0 0)
			(size 0.889 0.9906)
			(layers "F.Cu" "F.Mask" "F.Paste")
			(net "PVDDQ_KLM")
		)
		(pad "2" smd rect
			(at 0 1.397)
			(size 0.889 0.9906)
			(layers "F.Cu" "F.Mask" "F.Paste")
			(net "GND")
		)
		(zone
			(layer "F.Cu")
			(hatch none 0.5)
			(connect_pads
				(clearance 0)
			)
			(min_thickness 0.25)
			(keepout
				(tracks allowed)
				(vias not_allowed)
				(pads allowed)
				(copperpour not_allowed)
				(footprints allowed)
			)
			(placement
				(enabled no)
				(sheetname "")
			)
			(fill
				(thermal_gap 0.5)
				(thermal_bridge_width 0.5)
				(island_removal_mode 0)
			)
			(polygon
				(pts
					(xy 108.8136 -139.7127) (xy 108.8136 -140.7033) (xy 108.3056 -140.7033) (xy 108.3056 -139.7127)
				)
			)
		)
		(zone
			(layer "F.Cu")
			(hatch none 0.5)
			(connect_pads
				(clearance 0)
			)
			(min_thickness 0.25)
			(keepout
				(tracks not_allowed)
				(vias allowed)
				(pads allowed)
				(copperpour not_allowed)
				(footprints allowed)
			)
			(placement
				(enabled no)
				(sheetname "")
			)
			(fill
				(thermal_gap 0.5)
				(thermal_bridge_width 0.5)
				(island_removal_mode 0)
			)
			(polygon
				(pts
					(xy 108.8136 -139.7127) (xy 108.8136 -140.7033) (xy 108.3056 -140.7033) (xy 108.3056 -139.7127)
				)
			)
		)
	)
)
